#ISCELL
  pure_quanta quanta_title_block_c *
  *
#ISCELL
  standard offpage *
  page65_i1
#ISCELL
  standard tap *
  page65_i10
#ISCELL
  standard offpage *
  page65_i100
#ISCELL
  standard offpage *
  page65_i101
#ISCELL
  standard tap *
  page65_i11
#ISCELL
  standard tap *
  page65_i12
#ISCELL
  standard tap *
  page65_i13
#ISCELL
  standard tap *
  page65_i14
#ISCELL
  standard tap *
  page65_i15
#CELL
  pure_quanta socket4677_azif0045p001c01cs *
  page65_i16
#ISCELL
  standard tap *
  page65_i17
#ISCELL
  standard tap *
  page65_i18
#ISCELL
  standard tap *
  page65_i19
#ISCELL
  standard offpage *
  page65_i2
#ISCELL
  standard tap *
  page65_i20
#ISCELL
  standard tap *
  page65_i21
#ISCELL
  standard tap *
  page65_i22
#ISCELL
  standard tap *
  page65_i23
#ISCELL
  standard tap *
  page65_i24
#ISCELL
  standard tap *
  page65_i25
#ISCELL
  standard tap *
  page65_i26
#ISCELL
  standard tap *
  page65_i27
#ISCELL
  standard tap *
  page65_i28
#ISCELL
  standard tap *
  page65_i29
#ISCELL
  standard tap *
  page65_i3
#ISCELL
  standard tap *
  page65_i30
#ISCELL
  standard tap *
  page65_i31
#ISCELL
  standard tap *
  page65_i32
#ISCELL
  standard tap *
  page65_i33
#ISCELL
  standard tap *
  page65_i34
#ISCELL
  standard tap *
  page65_i35
#ISCELL
  standard tap *
  page65_i36
#ISCELL
  standard tap *
  page65_i37
#ISCELL
  standard tap *
  page65_i38
#ISCELL
  standard tap *
  page65_i39
#ISCELL
  standard tap *
  page65_i4
#ISCELL
  standard tap *
  page65_i40
#ISCELL
  standard tap *
  page65_i41
#ISCELL
  standard tap *
  page65_i42
#ISCELL
  standard tap *
  page65_i43
#ISCELL
  standard tap *
  page65_i44
#ISCELL
  standard tap *
  page65_i45
#ISCELL
  standard tap *
  page65_i46
#ISCELL
  standard tap *
  page65_i47
#ISCELL
  standard tap *
  page65_i48
#ISCELL
  standard tap *
  page65_i49
#ISCELL
  standard tap *
  page65_i5
#ISCELL
  standard tap *
  page65_i50
#ISCELL
  standard tap *
  page65_i51
#ISCELL
  standard tap *
  page65_i52
#ISCELL
  standard tap *
  page65_i53
#ISCELL
  standard tap *
  page65_i54
#ISCELL
  standard tap *
  page65_i55
#ISCELL
  standard tap *
  page65_i56
#ISCELL
  standard tap *
  page65_i57
#ISCELL
  standard tap *
  page65_i58
#ISCELL
  standard tap *
  page65_i59
#ISCELL
  standard tap *
  page65_i6
#ISCELL
  standard tap *
  page65_i60
#ISCELL
  standard tap *
  page65_i61
#ISCELL
  standard tap *
  page65_i62
#ISCELL
  standard tap *
  page65_i63
#ISCELL
  standard tap *
  page65_i64
#ISCELL
  standard tap *
  page65_i65
#ISCELL
  standard tap *
  page65_i66
#ISCELL
  standard tap *
  page65_i67
#ISCELL
  standard tap *
  page65_i68
#ISCELL
  standard tap *
  page65_i69
#ISCELL
  standard tap *
  page65_i7
#ISCELL
  standard tap *
  page65_i70
#ISCELL
  standard tap *
  page65_i71
#ISCELL
  standard tap *
  page65_i72
#ISCELL
  standard tap *
  page65_i73
#ISCELL
  standard tap *
  page65_i74
#ISCELL
  standard tap *
  page65_i75
#ISCELL
  standard tap *
  page65_i76
#ISCELL
  standard tap *
  page65_i77
#ISCELL
  standard tap *
  page65_i78
#ISCELL
  standard tap *
  page65_i79
#ISCELL
  standard tap *
  page65_i8
#ISCELL
  standard tap *
  page65_i80
#ISCELL
  standard tap *
  page65_i81
#ISCELL
  standard tap *
  page65_i82
#ISCELL
  standard tap *
  page65_i83
#ISCELL
  standard tap *
  page65_i84
#ISCELL
  standard tap *
  page65_i85
#ISCELL
  standard tap *
  page65_i86
#ISCELL
  standard tap *
  page65_i87
#ISCELL
  standard tap *
  page65_i88
#ISCELL
  standard tap *
  page65_i89
#ISCELL
  standard tap *
  page65_i9
#ISCELL
  standard tap *
  page65_i90
#ISCELL
  standard tap *
  page65_i91
#ISCELL
  standard tap *
  page65_i92
#ISCELL
  standard tap *
  page65_i93
#ISCELL
  standard tap *
  page65_i94
#ISCELL
  standard tap *
  page65_i95
#ISCELL
  standard tap *
  page65_i96
#ISCELL
  standard tap *
  page65_i97
#ISCELL
  standard tap *
  page65_i98
#ISCELL
  standard tap *
  page65_i99
